# T6G (Grand Teton) — schematic netlist excerpt (pin names and nets, part order shuffled) for the footprints in the layout excerpt that follows; sources: Cadence DE-HDL packaged netlist, KiCad conversion of 04192023_DAF0TMB3IC0_F0TG_MB_C_brd_V02_OCP.brd

PC6532  Q_CAPP  390UF 2.5V 20% ALUM  pkg SMLF  page 361 : A = P1V8_CPU1_RT_1D ; B = GND
R563  Q_RES  1K 1% EMPTY  pkg 0402LF  page 55 : A = PVDD11_S3_P1 ; B = I3C_0_SPD_DDRAF_CPU1_R_SCL
R1376  Q_RES  4.7K 5% CHIP  pkg 0201LF  page 331 : A = CLKREQ_RT_CPU1_P1_N ; B = GND

(kicad_pcb
	(version 20260206)
	(generator "pcbnew")
	(generator_version "10.0")
	(general
		(thickness 1.6)
		(legacy_teardrops no)
	)
	(paper "A4")
	(title_block
		(title "04192023_DAF0TMB3IC0_F0TG_MB_C_brd_V02_OCP.brd")
		(comment 1 "Grand Teton / footprints 3554-3556 of 8354")
	)
	(layers
		(0 "F.Cu" signal "TOP")
		(4 "In1.Cu" signal "GND")
		(6 "In2.Cu" signal "IN1")
		(8 "In3.Cu" signal "GND1")
		(10 "In4.Cu" signal "IN2")
		(12 "In5.Cu" signal "GND2")
		(14 "In6.Cu" signal "IN3")
		(16 "In7.Cu" signal "GND3")
		(18 "In8.Cu" signal "VCC")
		(20 "In9.Cu" signal "VCC1")
		(22 "In10.Cu" signal "GND4")
		(24 "In11.Cu" signal "IN4")
		(26 "In12.Cu" signal "GND5")
		(28 "In13.Cu" signal "IN5")
		(30 "In14.Cu" signal "GND6")
		(32 "In15.Cu" signal "IN6")
		(34 "In16.Cu" signal "GND7")
		(2 "B.Cu" signal "BOTTOM")
		(9 "F.Adhes" user "F.Adhesive")
		(11 "B.Adhes" user "B.Adhesive")
		(13 "F.Paste" user "Package Geometry/Pastemask Top")
		(15 "B.Paste" user "Package Geometry/Pastemask Bottom")
		(5 "F.SilkS" user "Ref Des/Silkscreen Top")
		(7 "B.SilkS" user "Ref Des/Silkscreen Bottom")
		(1 "F.Mask" user "Board Geometry/Soldermask Top")
		(3 "B.Mask" user "Board Geometry/Soldermask Bottom")
		(17 "Dwgs.User" user "User.Drawings")
		(19 "Cmts.User" user "User.Comments")
		(21 "Eco1.User" user "User.Eco1")
		(23 "Eco2.User" user "User.Eco2")
		(25 "Edge.Cuts" user "Board Geometry/Outline")
		(27 "Margin" user)
		(31 "F.CrtYd" user "Package Geometry/Place Bound Top")
		(29 "B.CrtYd" user "Package Geometry/Place Bound Bottom")
		(35 "F.Fab" user "Ref Des/Assembly Top")
		(33 "B.Fab" user "Ref Des/Assembly Bottom")
	)
	(footprint ""
		(layer "F.Cu")
		(at 45.212 -170.815 180)
		(property "Reference" "R563"
			(at 0 0 180)
			(layer "F.SilkS")
			(hide yes)
			(effects
				(font
					(size 1.27 1.27)
				)
			)
		)
		(property "Value" ""
			(at 0 0 180)
			(layer "F.Fab")
			(effects
				(font
					(size 1.27 1.27)
				)
			)
		)
		(duplicate_pad_numbers_are_jumpers no)
		(fp_line
			(start 0.7874 0.4064)
			(end -0.7874 0.4064)
			(stroke
				(width 0.1524)
				(type default)
			)
			(layer "F.SilkS")
		)
		(fp_line
			(start 0.7874 -0.4064)
			(end 0.7874 0.4064)
			(stroke
				(width 0.1524)
				(type default)
			)
			(layer "F.SilkS")
		)
		(fp_line
			(start -0.7874 0.4064)
			(end -0.7874 -0.4064)
			(stroke
				(width 0.1524)
				(type default)
			)
			(layer "F.SilkS")
		)
		(fp_line
			(start -0.7874 -0.4064)
			(end 0.7874 -0.4064)
			(stroke
				(width 0.1524)
				(type default)
			)
			(layer "F.SilkS")
		)
		(fp_line
			(start 0.67945 0.3048)
			(end 0.120396 0.3048)
			(stroke
				(width 0.1)
				(type default)
			)
			(layer "F.Fab")
		)
		(fp_line
			(start 0.67945 -0.3048)
			(end 0.67945 0.3048)
			(stroke
				(width 0.1)
				(type default)
			)
			(layer "F.Fab")
		)
		(fp_line
			(start 0.12065 -0.2794)
			(end 0.12065 -0.3048)
			(stroke
				(width 0.1)
				(type default)
			)
			(layer "F.Fab")
		)
		(fp_line
			(start 0.12065 -0.3048)
			(end 0.67945 -0.3048)
			(stroke
				(width 0.1)
				(type default)
			)
			(layer "F.Fab")
		)
		(fp_line
			(start 0.120396 0.3048)
			(end 0.120396 0.2794)
			(stroke
				(width 0.1)
				(type default)
			)
			(layer "F.Fab")
		)
		(fp_line
			(start 0.120396 0.2794)
			(end -0.12065 0.2794)
			(stroke
				(width 0.1)
				(type default)
			)
			(layer "F.Fab")
		)
		(fp_line
			(start -0.12065 0.3048)
			(end -0.67945 0.3048)
			(stroke
				(width 0.1)
				(type default)
			)
			(layer "F.Fab")
		)
		(fp_line
			(start -0.12065 0.2794)
			(end -0.12065 0.3048)
			(stroke
				(width 0.1)
				(type default)
			)
			(layer "F.Fab")
		)
		(fp_line
			(start -0.12065 -0.2794)
			(end 0.12065 -0.2794)
			(stroke
				(width 0.1)
				(type default)
			)
			(layer "F.Fab")
		)
		(fp_line
			(start -0.12065 -0.305054)
			(end -0.12065 -0.2794)
			(stroke
				(width 0.1)
				(type default)
			)
			(layer "F.Fab")
		)
		(fp_line
			(start -0.67945 0.3048)
			(end -0.67945 -0.305054)
			(stroke
				(width 0.1)
				(type default)
			)
			(layer "F.Fab")
		)
		(fp_line
			(start -0.67945 -0.305054)
			(end -0.12065 -0.305054)
			(stroke
				(width 0.1)
				(type default)
			)
			(layer "F.Fab")
		)
		(pad "1" smd circle
			(at -0.40005 0 180)
			(size 0 0)
			(layers "F.Cu" "F.Mask" "F.Paste")
			(net "PVDD11_S3_P1")
		)
		(pad "2" smd circle
			(at 0.40005 0 180)
			(size 0 0)
			(layers "F.Cu" "F.Mask" "F.Paste")
			(net "I3C_0_SPD_DDRAF_CPU1_R_SCL")
		)
	)
	(footprint ""
		(layer "F.Cu")
		(at 232.517442 -315.82868 90)
		(property "Reference" "PC6532"
			(at -1.50368 3.729228 90)
			(unlocked yes)
			(layer "F.SilkS")
			(effects
				(font
					(size 0.7874 0.5842)
					(thickness 0.1524)
				)
				(justify left)
			)
		)
		(property "Value" ""
			(at 0 0 90)
			(layer "F.Fab")
			(effects
				(font
					(size 1.27 1.27)
				)
			)
		)
		(duplicate_pad_numbers_are_jumpers no)
		(fp_line
			(start 2.750058 -2.750058)
			(end -1.988058 -2.750058)
			(stroke
				(width 0.1524)
				(type default)
			)
			(layer "F.SilkS")
		)
		(fp_line
			(start -1.988058 -2.750058)
			(end -2.750058 -1.988058)
			(stroke
				(width 0.1524)
				(type default)
			)
			(layer "F.SilkS")
		)
		(fp_line
			(start -2.750058 -1.988058)
			(end -2.750058 -0.9398)
			(stroke
				(width 0.1524)
				(type default)
			)
			(layer "F.SilkS")
		)
		(fp_line
			(start 2.750058 -0.9398)
			(end 2.750058 -2.750058)
			(stroke
				(width 0.1524)
				(type default)
			)
			(layer "F.SilkS")
		)
		(fp_line
			(start -2.750058 0.9398)
			(end -2.750058 1.988058)
			(stroke
				(width 0.1524)
				(type default)
			)
			(layer "F.SilkS")
		)
		(fp_line
			(start -2.750058 1.988058)
			(end -1.988058 2.750058)
			(stroke
				(width 0.1524)
				(type default)
			)
			(layer "F.SilkS")
		)
		(fp_line
			(start 2.750058 2.750058)
			(end 2.750058 0.9398)
			(stroke
				(width 0.1524)
				(type default)
			)
			(layer "F.SilkS")
		)
		(fp_line
			(start -1.988058 2.750058)
			(end 2.750058 2.750058)
			(stroke
				(width 0.1524)
				(type default)
			)
			(layer "F.SilkS")
		)
		(fp_line
			(start 2.750058 -2.750058)
			(end -2.750058 -2.750058)
			(stroke
				(width 0.1)
				(type default)
			)
			(layer "F.Fab")
		)
		(fp_line
			(start -2.750058 -2.750058)
			(end -2.750058 2.750058)
			(stroke
				(width 0.1)
				(type default)
			)
			(layer "F.Fab")
		)
		(fp_line
			(start 2.750058 2.750058)
			(end 2.750058 -2.750058)
			(stroke
				(width 0.1)
				(type default)
			)
			(layer "F.Fab")
		)
		(fp_line
			(start -2.750058 2.750058)
			(end 2.750058 2.750058)
			(stroke
				(width 0.1)
				(type default)
			)
			(layer "F.Fab")
		)
		(pad "1" smd rect
			(at -2.199894 0 180)
			(size 1.6002 3.0226)
			(layers "F.Cu" "F.Mask" "F.Paste")
			(net "P1V8_CPU1_RT_1D")
		)
		(pad "2" smd rect
			(at 2.199894 0 180)
			(size 1.6002 3.0226)
			(layers "F.Cu" "F.Mask" "F.Paste")
			(net "GND")
		)
	)
	(footprint ""
		(layer "F.Cu")
		(at 102.961948 -381.7874 180)
		(property "Reference" "R1376"
			(at 0 0 180)
			(layer "F.SilkS")
			(hide yes)
			(effects
				(font
					(size 1.27 1.27)
				)
			)
		)
		(property "Value" ""
			(at 0 0 180)
			(layer "F.Fab")
			(effects
				(font
					(size 1.27 1.27)
				)
			)
		)
		(duplicate_pad_numbers_are_jumpers no)
		(fp_line
			(start 0.32512 0.175006)
			(end -0.32512 0.175006)
			(stroke
				(width 0.1)
				(type default)
			)
			(layer "F.Fab")
		)
		(fp_line
			(start 0.32512 -0.175006)
			(end 0.32512 0.175006)
			(stroke
				(width 0.1)
				(type default)
			)
			(layer "F.Fab")
		)
		(fp_line
			(start -0.32512 0.175006)
			(end -0.32512 -0.175006)
			(stroke
				(width 0.1)
				(type default)
			)
			(layer "F.Fab")
		)
		(fp_line
			(start -0.32512 -0.175006)
			(end 0.32512 -0.175006)
			(stroke
				(width 0.1)
				(type default)
			)
			(layer "F.Fab")
		)
		(pad "1" smd rect
			(at -0.2667 0 180)
			(size 0.3048 0.381)
			(layers "F.Cu" "F.Mask" "F.Paste")
			(net "CLKREQ_RT_CPU1_P1_N")
		)
		(pad "2" smd rect
			(at 0.2667 0)
			(size 0.3048 0.381)
			(layers "F.Cu" "F.Mask" "F.Paste")
			(net "GND")
		)
	)
)
